# TIMECARD (Time Appliance Project (Time Card)) — schematic netlist excerpt (pin names and nets, part order shuffled) for the footprints in the layout excerpt that follows; sources: Cadence DE-HDL packaged netlist, KiCad conversion of R4006-B0001-02_R01.brd

R502  RESISTOR  4.7KOHM 1%  pkg SMC_0402R_H016  page 11 : \1\ = XP3R3V_FPGA ; \2\ = FPGA_IN_MAC_10MHZ_OUT
R173  RESISTOR  4.7KOHM 1%  pkg SMC_0402R_H016  page 25 : \1\ = SG ; \2\ = FPGA_IO_1

(kicad_pcb
	(version 20260206)
	(generator "pcbnew")
	(generator_version "10.0")
	(general
		(thickness 1.6)
		(legacy_teardrops no)
	)
	(paper "A4")
	(title_block
		(title "timecard-production-celestica-r4006 — R4006-B0001-02_R01.brd")
		(comment 1 "Time Appliance Project (Time Card) / footprints 1031-1032 of 1113")
	)
	(layers
		(0 "F.Cu" signal "TOP")
		(4 "In1.Cu" signal "L02_GND1")
		(6 "In2.Cu" signal "L03_SIG1")
		(8 "In3.Cu" signal "L04_GND2")
		(10 "In4.Cu" signal "L05_VCC1")
		(12 "In5.Cu" signal "L06_VCC2")
		(14 "In6.Cu" signal "L07_GND3")
		(16 "In7.Cu" signal "L08_SIG2")
		(18 "In8.Cu" signal "L09_GND4")
		(2 "B.Cu" signal "BOTTOM")
		(9 "F.Adhes" user "F.Adhesive")
		(11 "B.Adhes" user "B.Adhesive")
		(13 "F.Paste" user "Package Geometry/Pastemask Top")
		(15 "B.Paste" user "Package Geometry/Pastemask Bottom")
		(5 "F.SilkS" user "Ref Des/Silkscreen Top")
		(7 "B.SilkS" user "Ref Des/Silkscreen Bottom")
		(1 "F.Mask" user "Board Geometry/Soldermask Top")
		(3 "B.Mask" user "Board Geometry/Soldermask Bottom")
		(17 "Dwgs.User" user "User.Drawings")
		(19 "Cmts.User" user "User.Comments")
		(21 "Eco1.User" user "User.Eco1")
		(23 "Eco2.User" user "User.Eco2")
		(25 "Edge.Cuts" user "Board Geometry/Outline")
		(27 "Margin" user)
		(31 "F.CrtYd" user "Package Geometry/Place Bound Top")
		(29 "B.CrtYd" user "Package Geometry/Place Bound Bottom")
		(35 "F.Fab" user "Ref Des/Assembly Top")
		(33 "B.Fab" user "Ref Des/Assembly Bottom")
	)
	(footprint ""
		(layer "B.Cu")
		(at 99.5426 -64.2874 90)
		(property "Reference" "R173"
			(at 3.4036 0.11303 270)
			(unlocked yes)
			(layer "B.SilkS")
			(effects
				(font
					(size 0.7874 0.5842)
					(thickness 0.1524)
				)
				(justify mirror)
			)
		)
		(property "Value" "VAL*"
			(at -0.02032 2.13233 90)
			(unlocked yes)
			(layer "B.Fab")
			(hide yes)
			(effects
				(font
					(size 0.7874 0.5842)
					(thickness 0.1524)
				)
				(justify mirror)
			)
		)
		(property "Tolerance" "TOL*"
			(at -0.044704 3.05435 90)
			(unlocked yes)
			(layer "Cmts.User")
			(hide yes)
			(effects
				(font
					(size 0.7874 0.5842)
					(thickness 0.1524)
				)
				(justify mirror)
			)
		)
		(property "User Part Number" "PARTNUM*"
			(at -0.02032 4.024884 90)
			(unlocked yes)
			(layer "Cmts.User")
			(hide yes)
			(effects
				(font
					(size 0.7874 0.5842)
					(thickness 0.1524)
				)
				(justify mirror)
			)
		)
		(property "Device Type" "RESISTOR-G155-14701-01,4.7KOHMA"
			(at -0.008382 1.210564 90)
			(unlocked yes)
			(layer "B.Fab")
			(hide yes)
			(effects
				(font
					(size 0.7874 0.5842)
					(thickness 0.1524)
				)
				(justify mirror)
			)
		)
		(duplicate_pad_numbers_are_jumpers no)
		(fp_line
			(start 1.143 -0.5588)
			(end 1.143 0.5588)
			(stroke
				(width 0.1)
				(type default)
			)
			(layer "B.SilkS")
		)
		(fp_line
			(start -1.143 -0.5588)
			(end 1.143 -0.5588)
			(stroke
				(width 0.1)
				(type default)
			)
			(layer "B.SilkS")
		)
		(fp_line
			(start 1.143 0.5588)
			(end -1.143 0.5588)
			(stroke
				(width 0.1)
				(type default)
			)
			(layer "B.SilkS")
		)
		(fp_line
			(start -1.143 0.5588)
			(end -1.143 -0.5588)
			(stroke
				(width 0.1)
				(type default)
			)
			(layer "B.SilkS")
		)
		(fp_poly
			(pts
				(xy 1.143 0.5588) (xy -1.143 0.5588) (xy -1.143 -0.5588) (xy 1.143 -0.5588)
			)
			(stroke
				(width 0)
				(type default)
			)
			(fill no)
			(layer "B.CrtYd")
		)
		(fp_line
			(start 0.508 -0.3048)
			(end 0.508 0.3048)
			(stroke
				(width 0.1)
				(type default)
			)
			(layer "B.Fab")
		)
		(fp_line
			(start -0.508 -0.3048)
			(end 0.508 -0.3048)
			(stroke
				(width 0.1)
				(type default)
			)
			(layer "B.Fab")
		)
		(fp_line
			(start 0.508 0.3048)
			(end -0.508 0.3048)
			(stroke
				(width 0.1)
				(type default)
			)
			(layer "B.Fab")
		)
		(fp_line
			(start -0.508 0.3048)
			(end -0.508 -0.3048)
			(stroke
				(width 0.1)
				(type default)
			)
			(layer "B.Fab")
		)
		(pad "1" smd rect
			(at 0.5334 0 270)
			(size 0.7112 0.6096)
			(layers "B.Cu" "B.Mask" "B.Paste")
			(net "SG")
		)
		(pad "2" smd rect
			(at -0.5334 0 270)
			(size 0.7112 0.6096)
			(layers "B.Cu" "B.Mask" "B.Paste")
			(net "FPGA_IO_1")
		)
		(zone
			(layer "B.Cu")
			(hatch none 0.5)
			(connect_pads
				(clearance 0)
			)
			(min_thickness 0.25)
			(keepout
				(tracks not_allowed)
				(vias allowed)
				(pads allowed)
				(copperpour not_allowed)
				(footprints allowed)
			)
			(placement
				(enabled no)
				(sheetname "")
			)
			(fill
				(thermal_gap 0.5)
				(thermal_bridge_width 0.5)
				(island_removal_mode 0)
			)
			(polygon
				(pts
					(xy 99.8474 -64.3636) (xy 99.2378 -64.3636) (xy 99.2378 -64.2112) (xy 99.8474 -64.2112)
				)
			)
		)
		(zone
			(layer "B.Cu")
			(hatch none 0.5)
			(connect_pads
				(clearance 0)
			)
			(min_thickness 0.25)
			(keepout
				(tracks allowed)
				(vias not_allowed)
				(pads allowed)
				(copperpour not_allowed)
				(footprints allowed)
			)
			(placement
				(enabled no)
				(sheetname "")
			)
			(fill
				(thermal_gap 0.5)
				(thermal_bridge_width 0.5)
				(island_removal_mode 0)
			)
			(polygon
				(pts
					(xy 99.8474 -64.3636) (xy 99.2378 -64.3636) (xy 99.2378 -64.2112) (xy 99.8474 -64.2112)
				)
			)
		)
	)
	(footprint ""
		(layer "B.Cu")
		(at 116.346986 -46.823122)
		(property "Reference" "R502"
			(at -42.940986 2.658872 0)
			(unlocked yes)
			(layer "B.SilkS")
			(effects
				(font
					(size 0.635 0.4064)
					(thickness 0.1524)
				)
				(justify mirror)
			)
		)
		(property "Value" "VAL*"
			(at 0 3.718306 0)
			(unlocked yes)
			(layer "B.Fab")
			(hide yes)
			(effects
				(font
					(size 0.7874 0.5842)
					(thickness 0.127)
				)
				(justify mirror)
			)
		)
		(property "Tolerance" "TOL*"
			(at 0 4.861306 0)
			(unlocked yes)
			(layer "Cmts.User")
			(hide yes)
			(effects
				(font
					(size 0.7874 0.5842)
					(thickness 0.127)
				)
				(justify mirror)
			)
		)
		(property "User Part Number" "PARTNUM*"
			(at 0 2.575306 0)
			(unlocked yes)
			(layer "Cmts.User")
			(hide yes)
			(effects
				(font
					(size 0.7874 0.5842)
					(thickness 0.127)
				)
				(justify mirror)
			)
		)
		(property "Device Type" "RESISTOR-G155-12201-01,2.2KOHMA"
			(at 0 1.432306 0)
			(unlocked yes)
			(layer "B.Fab")
			(hide yes)
			(effects
				(font
					(size 0.7874 0.5842)
					(thickness 0.127)
				)
				(justify mirror)
			)
		)
		(duplicate_pad_numbers_are_jumpers no)
		(fp_line
			(start -0.970026 -0.4699)
			(end -0.970026 0.4699)
			(stroke
				(width 0.1)
				(type default)
			)
			(layer "B.SilkS")
		)
		(fp_line
			(start -0.970026 0.4699)
			(end 0.970026 0.4699)
			(stroke
				(width 0.1)
				(type default)
			)
			(layer "B.SilkS")
		)
		(fp_line
			(start 0.970026 -0.4699)
			(end -0.970026 -0.4699)
			(stroke
				(width 0.1)
				(type default)
			)
			(layer "B.SilkS")
		)
		(fp_line
			(start 0.970026 0.4699)
			(end 0.970026 -0.4699)
			(stroke
				(width 0.1)
				(type default)
			)
			(layer "B.SilkS")
		)
		(fp_poly
			(pts
				(xy 0.970026 0.4699) (xy -0.970026 0.4699) (xy -0.970026 -0.4699) (xy 0.970026 -0.4699)
			)
			(stroke
				(width 0)
				(type default)
			)
			(fill no)
			(layer "B.CrtYd")
		)
		(fp_line
			(start -0.508 -0.3048)
			(end -0.508 0.3048)
			(stroke
				(width 0.1)
				(type default)
			)
			(layer "B.Fab")
		)
		(fp_line
			(start -0.508 0.3048)
			(end 0.508 0.3048)
			(stroke
				(width 0.1)
				(type default)
			)
			(layer "B.Fab")
		)
		(fp_line
			(start 0.508 -0.3048)
			(end -0.508 -0.3048)
			(stroke
				(width 0.1)
				(type default)
			)
			(layer "B.Fab")
		)
		(fp_line
			(start 0.508 0.3048)
			(end 0.508 -0.3048)
			(stroke
				(width 0.1)
				(type default)
			)
			(layer "B.Fab")
		)
		(pad "1" smd circle
			(at 0.500126 0 180)
			(size 0.635 0.635)
			(layers "B.Cu" "B.Mask" "B.Paste")
			(net "XP3R3V_FPGA")
		)
		(pad "2" smd circle
			(at -0.500126 0 180)
			(size 0.635 0.635)
			(layers "B.Cu" "B.Mask" "B.Paste")
			(net "FPGA_IN_MAC_10MHZ_OUT")
		)
	)
)
